(kicad_pcb
	(version 20260206)
	(generator "pcbnew")
	(generator_version "10.0")
	(general
		(thickness 1.6)
		(legacy_teardrops no)
	)
	(paper "A4")
	(title_block
		(title "01162023_DA0F0TEBIF0_F0T_Expander_BD_F_brd_V02_OCP.brd")
		(comment 1 "Grand Teton / footprints 755-760 of 9728")
	)
	(layers
		(0 "F.Cu" signal "TOP")
		(4 "In1.Cu" signal "GND")
		(6 "In2.Cu" signal "VCC")
		(8 "In3.Cu" signal "VCC1")
		(10 "In4.Cu" signal "GND1")
		(12 "In5.Cu" signal "IN1")
		(14 "In6.Cu" signal "GND2")
		(16 "In7.Cu" signal "IN2")
		(18 "In8.Cu" signal "GND3")
		(20 "In9.Cu" signal "IN3")
		(22 "In10.Cu" signal "GND4")
		(24 "In11.Cu" signal "IN4")
		(26 "In12.Cu" signal "GND5")
		(28 "In13.Cu" signal "IN5")
		(30 "In14.Cu" signal "GND6")
		(32 "In15.Cu" signal "IN6")
		(34 "In16.Cu" signal "GND7")
		(2 "B.Cu" signal "BOTTOM")
		(9 "F.Adhes" user "F.Adhesive")
		(11 "B.Adhes" user "B.Adhesive")
		(13 "F.Paste" user "Package Geometry/Pastemask Top")
		(15 "B.Paste" user "Package Geometry/Pastemask Bottom")
		(5 "F.SilkS" user "Ref Des/Silkscreen Top")
		(7 "B.SilkS" user "Ref Des/Silkscreen Bottom")
		(1 "F.Mask" user "Board Geometry/Soldermask Top")
		(3 "B.Mask" user "Board Geometry/Soldermask Bottom")
		(17 "Dwgs.User" user "User.Drawings")
		(19 "Cmts.User" user "User.Comments")
		(21 "Eco1.User" user "User.Eco1")
		(23 "Eco2.User" user "User.Eco2")
		(25 "Edge.Cuts" user "Board Geometry/Outline")
		(27 "Margin" user)
		(31 "F.CrtYd" user "Package Geometry/Place Bound Top")
		(29 "B.CrtYd" user "Package Geometry/Place Bound Bottom")
		(35 "F.Fab" user "Ref Des/Assembly Top")
		(33 "B.Fab" user "Ref Des/Assembly Bottom")
	)
	(footprint ""
		(layer "F.Cu")
		(at 290.908994 -27.04973 180)
		(property "Reference" "C2773"
			(at 0 0 180)
			(layer "F.SilkS")
			(hide yes)
			(effects
				(font
					(size 1.27 1.27)
				)
			)
		)
		(property "Value" ""
			(at 0 0 180)
			(layer "F.Fab")
			(effects
				(font
					(size 1.27 1.27)
				)
			)
		)
		(duplicate_pad_numbers_are_jumpers no)
		(fp_line
			(start 0.7874 0.4064)
			(end -0.7874 0.4064)
			(stroke
				(width 0.1524)
				(type default)
			)
			(layer "F.SilkS")
		)
		(fp_line
			(start 0.7874 -0.4064)
			(end 0.7874 0.4064)
			(stroke
				(width 0.1524)
				(type default)
			)
			(layer "F.SilkS")
		)
		(fp_line
			(start -0.7874 0.4064)
			(end -0.7874 -0.4064)
			(stroke
				(width 0.1524)
				(type default)
			)
			(layer "F.SilkS")
		)
		(fp_line
			(start -0.7874 -0.4064)
			(end 0.7874 -0.4064)
			(stroke
				(width 0.1524)
				(type default)
			)
			(layer "F.SilkS")
		)
		(fp_line
			(start 0.67945 0.3048)
			(end 0.120396 0.3048)
			(stroke
				(width 0.1)
				(type default)
			)
			(layer "F.Fab")
		)
		(fp_line
			(start 0.67945 -0.3048)
			(end 0.67945 0.3048)
			(stroke
				(width 0.1)
				(type default)
			)
			(layer "F.Fab")
		)
		(fp_line
			(start 0.12065 -0.2794)
			(end 0.12065 -0.3048)
			(stroke
				(width 0.1)
				(type default)
			)
			(layer "F.Fab")
		)
		(fp_line
			(start 0.12065 -0.3048)
			(end 0.67945 -0.3048)
			(stroke
				(width 0.1)
				(type default)
			)
			(layer "F.Fab")
		)
		(fp_line
			(start 0.120396 0.3048)
			(end 0.120396 0.2794)
			(stroke
				(width 0.1)
				(type default)
			)
			(layer "F.Fab")
		)
		(fp_line
			(start 0.120396 0.2794)
			(end -0.12065 0.2794)
			(stroke
				(width 0.1)
				(type default)
			)
			(layer "F.Fab")
		)
		(fp_line
			(start -0.12065 0.3048)
			(end -0.67945 0.3048)
			(stroke
				(width 0.1)
				(type default)
			)
			(layer "F.Fab")
		)
		(fp_line
			(start -0.12065 0.2794)
			(end -0.12065 0.3048)
			(stroke
				(width 0.1)
				(type default)
			)
			(layer "F.Fab")
		)
		(fp_line
			(start -0.12065 -0.2794)
			(end 0.12065 -0.2794)
			(stroke
				(width 0.1)
				(type default)
			)
			(layer "F.Fab")
		)
		(fp_line
			(start -0.12065 -0.305054)
			(end -0.12065 -0.2794)
			(stroke
				(width 0.1)
				(type default)
			)
			(layer "F.Fab")
		)
		(fp_line
			(start -0.67945 0.3048)
			(end -0.67945 -0.305054)
			(stroke
				(width 0.1)
				(type default)
			)
			(layer "F.Fab")
		)
		(fp_line
			(start -0.67945 -0.305054)
			(end -0.12065 -0.305054)
			(stroke
				(width 0.1)
				(type default)
			)
			(layer "F.Fab")
		)
		(pad "1" smd circle
			(at -0.40005 0 180)
			(size 0 0)
			(layers "F.Cu" "F.Mask" "F.Paste")
			(net "PRSNT_SSD10_R_N")
		)
		(pad "2" smd circle
			(at 0.40005 0 180)
			(size 0 0)
			(layers "F.Cu" "F.Mask" "F.Paste")
			(net "GND")
		)
	)
	(footprint ""
		(layer "F.Cu")
		(at 286.525462 -356.244906 90)
		(property "Reference" "C2359"
			(at 0 0 90)
			(layer "F.SilkS")
			(hide yes)
			(effects
				(font
					(size 1.27 1.27)
				)
			)
		)
		(property "Value" ""
			(at 0 0 90)
			(layer "F.Fab")
			(effects
				(font
					(size 1.27 1.27)
				)
			)
		)
		(duplicate_pad_numbers_are_jumpers no)
		(fp_line
			(start 0.299974 -0.150114)
			(end 0.299974 0.150114)
			(stroke
				(width 0.1)
				(type default)
			)
			(layer "F.Fab")
		)
		(fp_line
			(start -0.299974 -0.150114)
			(end 0.299974 -0.150114)
			(stroke
				(width 0.1)
				(type default)
			)
			(layer "F.Fab")
		)
		(fp_line
			(start 0.299974 0.150114)
			(end -0.299974 0.150114)
			(stroke
				(width 0.1)
				(type default)
			)
			(layer "F.Fab")
		)
		(fp_line
			(start -0.299974 0.150114)
			(end -0.299974 -0.150114)
			(stroke
				(width 0.1)
				(type default)
			)
			(layer "F.Fab")
		)
		(pad "1" smd rect
			(at -0.2667 0 90)
			(size 0.3048 0.381)
			(layers "F.Cu" "F.Mask" "F.Paste")
			(net "P5E_PEX2_STN4_TX_DP<70>")
		)
		(pad "2" smd rect
			(at 0.2667 0 90)
			(size 0.3048 0.381)
			(layers "F.Cu" "F.Mask" "F.Paste")
			(net "P5E_PEX2_STN4_TX_C_DP<70>")
		)
	)
	(footprint ""
		(layer "F.Cu")
		(at 9.64057 -294.47744 -90)
		(property "Reference" "PL18"
			(at -1.673352 -7.272274 90)
			(unlocked yes)
			(layer "F.SilkS")
			(effects
				(font
					(size 0.7874 0.5842)
					(thickness 0.1524)
				)
				(justify left)
			)
		)
		(property "Value" ""
			(at 0 0 270)
			(layer "F.Fab")
			(effects
				(font
					(size 1.27 1.27)
				)
			)
		)
		(duplicate_pad_numbers_are_jumpers no)
		(fp_line
			(start -6.849872 6.450076)
			(end -6.849872 1.9812)
			(stroke
				(width 0.1524)
				(type default)
			)
			(layer "F.SilkS")
		)
		(fp_line
			(start 6.849872 6.450076)
			(end -6.849872 6.450076)
			(stroke
				(width 0.1524)
				(type default)
			)
			(layer "F.SilkS")
		)
		(fp_line
			(start 6.849872 1.9812)
			(end 6.849872 6.450076)
			(stroke
				(width 0.1524)
				(type default)
			)
			(layer "F.SilkS")
		)
		(fp_line
			(start -6.849872 -1.9812)
			(end -6.849872 -6.450076)
			(stroke
				(width 0.1524)
				(type default)
			)
			(layer "F.SilkS")
		)
		(fp_line
			(start -6.849872 -6.450076)
			(end 6.849872 -6.450076)
			(stroke
				(width 0.1524)
				(type default)
			)
			(layer "F.SilkS")
		)
		(fp_line
			(start 6.849872 -6.450076)
			(end 6.849872 -1.9812)
			(stroke
				(width 0.1524)
				(type default)
			)
			(layer "F.SilkS")
		)
		(fp_line
			(start -6.849872 6.450076)
			(end -6.849872 -6.450076)
			(stroke
				(width 0.1)
				(type default)
			)
			(layer "F.Fab")
		)
		(fp_line
			(start 6.849872 6.450076)
			(end -6.849872 6.450076)
			(stroke
				(width 0.1)
				(type default)
			)
			(layer "F.Fab")
		)
		(fp_line
			(start -6.849872 -6.450076)
			(end 6.849872 -6.450076)
			(stroke
				(width 0.1)
				(type default)
			)
			(layer "F.Fab")
		)
		(fp_line
			(start 6.849872 -6.450076)
			(end 6.849872 6.450076)
			(stroke
				(width 0.1)
				(type default)
			)
			(layer "F.Fab")
		)
		(pad "1" smd rect
			(at -5.407406 0 270)
			(size 2.9464 3.7084)
			(layers "F.Cu" "F.Mask" "F.Paste")
			(net "SW_P1V25_PEX0_PH")
		)
		(pad "2" smd rect
			(at 5.407406 0 270)
			(size 2.9464 3.7084)
			(layers "F.Cu" "F.Mask" "F.Paste")
			(net "P1V25_PEX0_R")
		)
	)
	(footprint ""
		(layer "F.Cu")
		(at 196.975222 -63.086234)
		(property "Reference" "R5989"
			(at 0 0 0)
			(layer "F.SilkS")
			(hide yes)
			(effects
				(font
					(size 1.27 1.27)
				)
			)
		)
		(property "Value" ""
			(at 0 0 0)
			(layer "F.Fab")
			(effects
				(font
					(size 1.27 1.27)
				)
			)
		)
		(duplicate_pad_numbers_are_jumpers no)
		(fp_line
			(start -0.7874 -0.4064)
			(end 0.7874 -0.4064)
			(stroke
				(width 0.1524)
				(type default)
			)
			(layer "F.SilkS")
		)
		(fp_line
			(start -0.7874 0.4064)
			(end -0.7874 -0.4064)
			(stroke
				(width 0.1524)
				(type default)
			)
			(layer "F.SilkS")
		)
		(fp_line
			(start 0.7874 -0.4064)
			(end 0.7874 0.4064)
			(stroke
				(width 0.1524)
				(type default)
			)
			(layer "F.SilkS")
		)
		(fp_line
			(start 0.7874 0.4064)
			(end -0.7874 0.4064)
			(stroke
				(width 0.1524)
				(type default)
			)
			(layer "F.SilkS")
		)
		(fp_line
			(start -0.67945 -0.305054)
			(end -0.12065 -0.305054)
			(stroke
				(width 0.1)
				(type default)
			)
			(layer "F.Fab")
		)
		(fp_line
			(start -0.67945 0.3048)
			(end -0.67945 -0.305054)
			(stroke
				(width 0.1)
				(type default)
			)
			(layer "F.Fab")
		)
		(fp_line
			(start -0.12065 -0.305054)
			(end -0.12065 -0.2794)
			(stroke
				(width 0.1)
				(type default)
			)
			(layer "F.Fab")
		)
		(fp_line
			(start -0.12065 -0.2794)
			(end 0.12065 -0.2794)
			(stroke
				(width 0.1)
				(type default)
			)
			(layer "F.Fab")
		)
		(fp_line
			(start -0.12065 0.2794)
			(end -0.12065 0.3048)
			(stroke
				(width 0.1)
				(type default)
			)
			(layer "F.Fab")
		)
		(fp_line
			(start -0.12065 0.3048)
			(end -0.67945 0.3048)
			(stroke
				(width 0.1)
				(type default)
			)
			(layer "F.Fab")
		)
		(fp_line
			(start 0.120396 0.2794)
			(end -0.12065 0.2794)
			(stroke
				(width 0.1)
				(type default)
			)
			(layer "F.Fab")
		)
		(fp_line
			(start 0.120396 0.3048)
			(end 0.120396 0.2794)
			(stroke
				(width 0.1)
				(type default)
			)
			(layer "F.Fab")
		)
		(fp_line
			(start 0.12065 -0.3048)
			(end 0.67945 -0.3048)
			(stroke
				(width 0.1)
				(type default)
			)
			(layer "F.Fab")
		)
		(fp_line
			(start 0.12065 -0.2794)
			(end 0.12065 -0.3048)
			(stroke
				(width 0.1)
				(type default)
			)
			(layer "F.Fab")
		)
		(fp_line
			(start 0.67945 -0.3048)
			(end 0.67945 0.3048)
			(stroke
				(width 0.1)
				(type default)
			)
			(layer "F.Fab")
		)
		(fp_line
			(start 0.67945 0.3048)
			(end 0.120396 0.3048)
			(stroke
				(width 0.1)
				(type default)
			)
			(layer "F.Fab")
		)
		(pad "1" smd circle
			(at -0.40005 0)
			(size 0 0)
			(layers "F.Cu" "F.Mask" "F.Paste")
			(net "P12V_SSD7_R")
		)
		(pad "2" smd circle
			(at 0.40005 0)
			(size 0 0)
			(layers "F.Cu" "F.Mask" "F.Paste")
			(net "P12V_SSD7_PG_G1")
		)
	)
	(footprint ""
		(layer "F.Cu")
		(at 419.826694 -55.418228 90)
		(property "Reference" "PC430"
			(at 0 0 90)
			(layer "F.SilkS")
			(hide yes)
			(effects
				(font
					(size 1.27 1.27)
				)
			)
		)
		(property "Value" ""
			(at 0 0 90)
			(layer "F.Fab")
			(effects
				(font
					(size 1.27 1.27)
				)
			)
		)
		(duplicate_pad_numbers_are_jumpers no)
		(fp_line
			(start 0.7874 -0.4064)
			(end 0.7874 0.4064)
			(stroke
				(width 0.1524)
				(type default)
			)
			(layer "F.SilkS")
		)
		(fp_line
			(start -0.7874 -0.4064)
			(end 0.7874 -0.4064)
			(stroke
				(width 0.1524)
				(type default)
			)
			(layer "F.SilkS")
		)
		(fp_line
			(start 0.7874 0.4064)
			(end -0.7874 0.4064)
			(stroke
				(width 0.1524)
				(type default)
			)
			(layer "F.SilkS")
		)
		(fp_line
			(start -0.7874 0.4064)
			(end -0.7874 -0.4064)
			(stroke
				(width 0.1524)
				(type default)
			)
			(layer "F.SilkS")
		)
		(fp_line
			(start -0.12065 -0.305054)
			(end -0.12065 -0.2794)
			(stroke
				(width 0.1)
				(type default)
			)
			(layer "F.Fab")
		)
		(fp_line
			(start -0.67945 -0.305054)
			(end -0.12065 -0.305054)
			(stroke
				(width 0.1)
				(type default)
			)
			(layer "F.Fab")
		)
		(fp_line
			(start 0.67945 -0.3048)
			(end 0.67945 0.3048)
			(stroke
				(width 0.1)
				(type default)
			)
			(layer "F.Fab")
		)
		(fp_line
			(start 0.12065 -0.3048)
			(end 0.67945 -0.3048)
			(stroke
				(width 0.1)
				(type default)
			)
			(layer "F.Fab")
		)
		(fp_line
			(start 0.12065 -0.2794)
			(end 0.12065 -0.3048)
			(stroke
				(width 0.1)
				(type default)
			)
			(layer "F.Fab")
		)
		(fp_line
			(start -0.12065 -0.2794)
			(end 0.12065 -0.2794)
			(stroke
				(width 0.1)
				(type default)
			)
			(layer "F.Fab")
		)
		(fp_line
			(start 0.120396 0.2794)
			(end -0.12065 0.2794)
			(stroke
				(width 0.1)
				(type default)
			)
			(layer "F.Fab")
		)
		(fp_line
			(start -0.12065 0.2794)
			(end -0.12065 0.3048)
			(stroke
				(width 0.1)
				(type default)
			)
			(layer "F.Fab")
		)
		(fp_line
			(start 0.67945 0.3048)
			(end 0.120396 0.3048)
			(stroke
				(width 0.1)
				(type default)
			)
			(layer "F.Fab")
		)
		(fp_line
			(start 0.120396 0.3048)
			(end 0.120396 0.2794)
			(stroke
				(width 0.1)
				(type default)
			)
			(layer "F.Fab")
		)
		(fp_line
			(start -0.12065 0.3048)
			(end -0.67945 0.3048)
			(stroke
				(width 0.1)
				(type default)
			)
			(layer "F.Fab")
		)
		(fp_line
			(start -0.67945 0.3048)
			(end -0.67945 -0.305054)
			(stroke
				(width 0.1)
				(type default)
			)
			(layer "F.Fab")
		)
		(pad "1" smd circle
			(at -0.40005 0 90)
			(size 0 0)
			(layers "F.Cu" "F.Mask" "F.Paste")
			(net "P12V_SSD14_R")
		)
		(pad "2" smd circle
			(at 0.40005 0 90)
			(size 0 0)
			(layers "F.Cu" "F.Mask" "F.Paste")
			(net "GND")
		)
	)
	(footprint ""
		(layer "F.Cu")
		(at 29.422344 -252.356874 -90)
		(property "Reference" "R1193"
			(at 0 0 270)
			(layer "F.SilkS")
			(hide yes)
			(effects
				(font
					(size 1.27 1.27)
				)
			)
		)
		(property "Value" ""
			(at 0 0 270)
			(layer "F.Fab")
			(effects
				(font
					(size 1.27 1.27)
				)
			)
		)
		(duplicate_pad_numbers_are_jumpers no)
		(fp_line
			(start -0.7874 0.4064)
			(end -0.7874 -0.4064)
			(stroke
				(width 0.1524)
				(type default)
			)
			(layer "F.SilkS")
		)
		(fp_line
			(start 0.7874 0.4064)
			(end -0.7874 0.4064)
			(stroke
				(width 0.1524)
				(type default)
			)
			(layer "F.SilkS")
		)
		(fp_line
			(start -0.7874 -0.4064)
			(end 0.7874 -0.4064)
			(stroke
				(width 0.1524)
				(type default)
			)
			(layer "F.SilkS")
		)
		(fp_line
			(start 0.7874 -0.4064)
			(end 0.7874 0.4064)
			(stroke
				(width 0.1524)
				(type default)
			)
			(layer "F.SilkS")
		)
		(fp_line
			(start -0.67945 0.3048)
			(end -0.67945 -0.305054)
			(stroke
				(width 0.1)
				(type default)
			)
			(layer "F.Fab")
		)
		(fp_line
			(start -0.12065 0.3048)
			(end -0.67945 0.3048)
			(stroke
				(width 0.1)
				(type default)
			)
			(layer "F.Fab")
		)
		(fp_line
			(start 0.120396 0.3048)
			(end 0.120396 0.2794)
			(stroke
				(width 0.1)
				(type default)
			)
			(layer "F.Fab")
		)
		(fp_line
			(start 0.67945 0.3048)
			(end 0.120396 0.3048)
			(stroke
				(width 0.1)
				(type default)
			)
			(layer "F.Fab")
		)
		(fp_line
			(start -0.12065 0.2794)
			(end -0.12065 0.3048)
			(stroke
				(width 0.1)
				(type default)
			)
			(layer "F.Fab")
		)
		(fp_line
			(start 0.120396 0.2794)
			(end -0.12065 0.2794)
			(stroke
				(width 0.1)
				(type default)
			)
			(layer "F.Fab")
		)
		(fp_line
			(start -0.12065 -0.2794)
			(end 0.12065 -0.2794)
			(stroke
				(width 0.1)
				(type default)
			)
			(layer "F.Fab")
		)
		(fp_line
			(start 0.12065 -0.2794)
			(end 0.12065 -0.3048)
			(stroke
				(width 0.1)
				(type default)
			)
			(layer "F.Fab")
		)
		(fp_line
			(start 0.12065 -0.3048)
			(end 0.67945 -0.3048)
			(stroke
				(width 0.1)
				(type default)
			)
			(layer "F.Fab")
		)
		(fp_line
			(start 0.67945 -0.3048)
			(end 0.67945 0.3048)
			(stroke
				(width 0.1)
				(type default)
			)
			(layer "F.Fab")
		)
		(fp_line
			(start -0.67945 -0.305054)
			(end -0.12065 -0.305054)
			(stroke
				(width 0.1)
				(type default)
			)
			(layer "F.Fab")
		)
		(fp_line
			(start -0.12065 -0.305054)
			(end -0.12065 -0.2794)
			(stroke
				(width 0.1)
				(type default)
			)
			(layer "F.Fab")
		)
		(pad "1" smd circle
			(at -0.40005 0 270)
			(size 0 0)
			(layers "F.Cu" "F.Mask" "F.Paste")
			(net "GND")
		)
		(pad "2" smd circle
			(at 0.40005 0 270)
			(size 0 0)
			(layers "F.Cu" "F.Mask" "F.Paste")
			(net "PEX0_MODE_SEL3")
		)
	)
)
